(kicad_pcb
	(version 20241229)
	(generator "pcbnew")
	(generator_version "9.0")
	(general
		(thickness 1.711)
		(legacy_teardrops no)
	)
	(paper "A4")
	(title_block
		(title "Antmicro Baseboard for Jetson AGX Thor")
		(date "2026-02-18")
		(rev "1.1.0")
		(company "Antmicro Ltd")
		(comment 1 "www.antmicro.com")
		(comment 9 "footprints 1061-1065 of 1170")
	)
	(layers
		(0 "F.Cu" signal)
		(4 "In1.Cu" signal)
		(6 "In2.Cu" signal)
		(8 "In3.Cu" signal)
		(10 "In4.Cu" jumper)
		(12 "In5.Cu" signal)
		(14 "In6.Cu" signal)
		(16 "In7.Cu" signal)
		(18 "In8.Cu" signal)
		(2 "B.Cu" signal)
		(9 "F.Adhes" user "F.Adhesive")
		(11 "B.Adhes" user "B.Adhesive")
		(13 "F.Paste" user)
		(15 "B.Paste" user)
		(5 "F.SilkS" user "F.Silkscreen")
		(7 "B.SilkS" user "B.Silkscreen")
		(1 "F.Mask" user)
		(3 "B.Mask" user)
		(17 "Dwgs.User" user "User.Drawings")
		(19 "Cmts.User" user "User.Comments")
		(21 "Eco1.User" user "User.Eco1")
		(23 "Eco2.User" user "User.Eco2")
		(25 "Edge.Cuts" user)
		(27 "Margin" user)
		(31 "F.CrtYd" user "F.Courtyard")
		(29 "B.CrtYd" user "B.Courtyard")
		(35 "F.Fab" user)
		(33 "B.Fab" user)
	)
	(footprint "antmicro-footprints:C_0402_1005Metric"
		(layer "B.Cu")
		(at 123.79 70.68 180)
		(descr "Capacitor SMD 0402")
		(tags "capacitor SMD 0402")
		(property "Reference" "C25"
			(at -3.06 -0.39 0)
			(layer "B.SilkS")
			(effects
				(font
					(size 0.7 0.7)
					(thickness 0.15)
				)
				(justify left bottom mirror)
			)
		)
		(property "Value" "C_10u_0402"
			(at -1.022927 -2.155213 0)
			(layer "B.Fab")
			(effects
				(font
					(size 0.7 0.7)
					(thickness 0.15)
				)
				(justify left bottom mirror)
			)
		)
		(property "Datasheet" "https://www.yageo.com/en/Chart/Download/pdf/CC0402MRX5R5BB106"
			(at 0 0 0)
			(layer "B.Fab")
			(hide yes)
			(effects
				(font
					(size 1.27 1.27)
					(thickness 0.15)
				)
				(justify mirror)
			)
		)
		(property "Description" "SMD Multilayer Ceramic Capacitor, 10 µF, 6.3 V, 0402 [1005 Metric], ± 20%, X5R, CC Series"
			(at 0 0 0)
			(layer "B.Fab")
			(hide yes)
			(effects
				(font
					(size 1.27 1.27)
					(thickness 0.15)
				)
				(justify mirror)
			)
		)
		(property "MPN" "CC0402MRX5R5BB106"
			(at 0 0 180)
			(unlocked yes)
			(layer "B.Fab")
			(hide yes)
			(effects
				(font
					(size 1 1)
					(thickness 0.15)
				)
				(justify mirror)
			)
		)
		(property "Manufacturer" "YAGEO"
			(at 0 0 180)
			(unlocked yes)
			(layer "B.Fab")
			(hide yes)
			(effects
				(font
					(size 1 1)
					(thickness 0.15)
				)
				(justify mirror)
			)
		)
		(property "License" "Apache-2.0"
			(at 0 0 180)
			(unlocked yes)
			(layer "B.Fab")
			(hide yes)
			(effects
				(font
					(size 1 1)
					(thickness 0.15)
				)
				(justify mirror)
			)
		)
		(property "Author" "Antmicro"
			(at 0 0 180)
			(unlocked yes)
			(layer "B.Fab")
			(hide yes)
			(effects
				(font
					(size 1 1)
					(thickness 0.15)
				)
				(justify mirror)
			)
		)
		(property "Val" "10u"
			(at 0 0 180)
			(unlocked yes)
			(layer "B.Fab")
			(hide yes)
			(effects
				(font
					(size 1 1)
					(thickness 0.15)
				)
				(justify mirror)
			)
		)
		(property "Voltage" ""
			(at 0 0 180)
			(unlocked yes)
			(layer "B.Fab")
			(hide yes)
			(effects
				(font
					(size 1 1)
					(thickness 0.15)
				)
				(justify mirror)
			)
		)
		(property "Dielectric" "template_dielectric"
			(at 0 0 180)
			(unlocked yes)
			(layer "B.Fab")
			(hide yes)
			(effects
				(font
					(size 1 1)
					(thickness 0.15)
				)
				(justify mirror)
			)
		)
		(sheetname "/SoM_Power/")
		(sheetfile "som_power.kicad_sch")
		(attr smd)
		(fp_rect
			(start -0.925 0.47)
			(end 0.925 -0.47)
			(stroke
				(width 0.05)
				(type default)
			)
			(fill no)
			(layer "B.CrtYd")
		)
		(fp_line
			(start 0.504 0.25)
			(end 0.504 -0.248)
			(stroke
				(width 0.15)
				(type solid)
			)
			(layer "B.Fab")
		)
		(fp_line
			(start 0.504 -0.248)
			(end -0.494 -0.248)
			(stroke
				(width 0.15)
				(type solid)
			)
			(layer "B.Fab")
		)
		(fp_line
			(start -0.494 0.25)
			(end 0.504 0.25)
			(stroke
				(width 0.15)
				(type solid)
			)
			(layer "B.Fab")
		)
		(fp_line
			(start -0.494 -0.248)
			(end -0.494 0.25)
			(stroke
				(width 0.15)
				(type solid)
			)
			(layer "B.Fab")
		)
		(fp_text user "${REFERENCE}"
			(at -0.939 -4.599 0)
			(layer "B.Fab")
			(effects
				(font
					(size 0.7 0.7)
					(thickness 0.15)
				)
				(justify left bottom mirror)
			)
		)
		(fp_text user "License: Apache-2.0"
			(at -0.939 -5.799 0)
			(layer "B.Fab")
			(effects
				(font
					(size 0.7 0.7)
					(thickness 0.15)
				)
				(justify left bottom mirror)
			)
		)
		(fp_text user "Author: Antmicro"
			(at -0.939 -3.399 0)
			(layer "B.Fab")
			(effects
				(font
					(size 0.7 0.7)
					(thickness 0.15)
				)
				(justify left bottom mirror)
			)
		)
		(pad "1" smd roundrect
			(at -0.48 0 180)
			(size 0.59 0.64)
			(layers "B.Cu" "B.Mask" "B.Paste")
			(roundrect_rratio 0.25)
			(net 1 "GND")
			(pintype "passive")
		)
		(pad "2" smd roundrect
			(at 0.48 0 180)
			(size 0.59 0.64)
			(layers "B.Cu" "B.Mask" "B.Paste")
			(roundrect_rratio 0.25)
			(net 213 "+5V_SOM")
			(pintype "passive")
		)
	)
	(footprint "antmicro-footprints:C_0402_1005Metric"
		(layer "B.Cu")
		(at 205.226 150.6 180)
		(descr "Capacitor SMD 0402")
		(tags "capacitor SMD 0402")
		(property "Reference" "C173"
			(at -1.14 0.699 0)
			(layer "B.SilkS")
			(effects
				(font
					(size 0.7 0.7)
					(thickness 0.15)
				)
				(justify left bottom mirror)
			)
		)
		(property "Value" "C_100n_0402"
			(at -1.022927 -2.155213 0)
			(layer "B.Fab")
			(effects
				(font
					(size 0.7 0.7)
					(thickness 0.15)
				)
				(justify left bottom mirror)
			)
		)
		(property "Datasheet" "https://www.murata.com/products/productdetail?partno=GRM155R61H104KE14%23"
			(at 0 0 0)
			(layer "B.Fab")
			(hide yes)
			(effects
				(font
					(size 1.27 1.27)
					(thickness 0.15)
				)
				(justify mirror)
			)
		)
		(property "Description" "SMD Multilayer Ceramic Capacitor, 0.1 µF, 50 V, 0402 [1005 Metric], ± 10%, X5R, GRM Series"
			(at 0 0 0)
			(layer "B.Fab")
			(hide yes)
			(effects
				(font
					(size 1.27 1.27)
					(thickness 0.15)
				)
				(justify mirror)
			)
		)
		(property "MPN" "GRM155R61H104KE14D"
			(at 0 0 0)
			(unlocked yes)
			(layer "B.Fab")
			(hide yes)
			(effects
				(font
					(size 1 1)
					(thickness 0.15)
				)
				(justify mirror)
			)
		)
		(property "Manufacturer" "Murata"
			(at 0 0 0)
			(unlocked yes)
			(layer "B.Fab")
			(hide yes)
			(effects
				(font
					(size 1 1)
					(thickness 0.15)
				)
				(justify mirror)
			)
		)
		(property "License" "Apache-2.0"
			(at 0 0 0)
			(unlocked yes)
			(layer "B.Fab")
			(hide yes)
			(effects
				(font
					(size 1 1)
					(thickness 0.15)
				)
				(justify mirror)
			)
		)
		(property "Author" "Antmicro"
			(at 0 0 0)
			(unlocked yes)
			(layer "B.Fab")
			(hide yes)
			(effects
				(font
					(size 1 1)
					(thickness 0.15)
				)
				(justify mirror)
			)
		)
		(property "Val" "100n"
			(at 0 0 0)
			(unlocked yes)
			(layer "B.Fab")
			(hide yes)
			(effects
				(font
					(size 1 1)
					(thickness 0.15)
				)
				(justify mirror)
			)
		)
		(property "Voltage" "50V"
			(at 0 0 0)
			(unlocked yes)
			(layer "B.Fab")
			(hide yes)
			(effects
				(font
					(size 1 1)
					(thickness 0.15)
				)
				(justify mirror)
			)
		)
		(property "Dielectric" "X5R"
			(at 0 0 0)
			(unlocked yes)
			(layer "B.Fab")
			(hide yes)
			(effects
				(font
					(size 1 1)
					(thickness 0.15)
				)
				(justify mirror)
			)
		)
		(sheetname "/SFP/")
		(sheetfile "sfp.kicad_sch")
		(attr smd)
		(fp_rect
			(start -0.925 0.47)
			(end 0.925 -0.47)
			(stroke
				(width 0.05)
				(type default)
			)
			(fill no)
			(layer "B.CrtYd")
		)
		(fp_line
			(start 0.504 0.25)
			(end 0.504 -0.248)
			(stroke
				(width 0.15)
				(type solid)
			)
			(layer "B.Fab")
		)
		(fp_line
			(start 0.504 -0.248)
			(end -0.494 -0.248)
			(stroke
				(width 0.15)
				(type solid)
			)
			(layer "B.Fab")
		)
		(fp_line
			(start -0.494 0.25)
			(end 0.504 0.25)
			(stroke
				(width 0.15)
				(type solid)
			)
			(layer "B.Fab")
		)
		(fp_line
			(start -0.494 -0.248)
			(end -0.494 0.25)
			(stroke
				(width 0.15)
				(type solid)
			)
			(layer "B.Fab")
		)
		(fp_text user "License: Apache-2.0"
			(at -0.939 -5.799 0)
			(layer "B.Fab")
			(effects
				(font
					(size 0.7 0.7)
					(thickness 0.15)
				)
				(justify left bottom mirror)
			)
		)
		(fp_text user "${REFERENCE}"
			(at -0.939 -4.599 0)
			(layer "B.Fab")
			(effects
				(font
					(size 0.7 0.7)
					(thickness 0.15)
				)
				(justify left bottom mirror)
			)
		)
		(fp_text user "Author: Antmicro"
			(at -0.939 -3.399 0)
			(layer "B.Fab")
			(effects
				(font
					(size 0.7 0.7)
					(thickness 0.15)
				)
				(justify left bottom mirror)
			)
		)
		(pad "1" smd roundrect
			(at -0.48 0 180)
			(size 0.59 0.64)
			(layers "B.Cu" "B.Mask" "B.Paste")
			(roundrect_rratio 0.25)
			(net 1 "GND")
			(pintype "passive")
		)
		(pad "2" smd roundrect
			(at 0.48 0 180)
			(size 0.59 0.64)
			(layers "B.Cu" "B.Mask" "B.Paste")
			(roundrect_rratio 0.25)
			(net 379 "/SFP/SH")
			(pintype "passive")
		)
	)
	(footprint "antmicro-footprints:C_0805_2012Metric"
		(layer "B.Cu")
		(at 100.1 132.3 180)
		(descr "Capacitor SMD 0805")
		(tags "capacitor SMD 0805")
		(property "Reference" "C230"
			(at -5.1 -0.5 0)
			(layer "B.SilkS")
			(effects
				(font
					(size 0.7 0.7)
					(thickness 0.15)
				)
				(justify left bottom mirror)
			)
		)
		(property "Value" "C_22u_25V_0805"
			(at -2.055717 -1.963152 0)
			(layer "B.Fab")
			(effects
				(font
					(size 0.7 0.7)
					(thickness 0.15)
				)
				(justify left bottom mirror)
			)
		)
		(property "Datasheet" "https://product.samsungsem.com/mlcc/CL21A226MAYNNN.do"
			(at 0 0 0)
			(layer "B.Fab")
			(hide yes)
			(effects
				(font
					(size 1.27 1.27)
					(thickness 0.15)
				)
				(justify mirror)
			)
		)
		(property "Description" "SMT Multilayer Ceramic Capacitor, 22uF, +/-20%, 25V, X5R, 0805 [2012 Metric]"
			(at 0 0 0)
			(layer "B.Fab")
			(hide yes)
			(effects
				(font
					(size 1.27 1.27)
					(thickness 0.15)
				)
				(justify mirror)
			)
		)
		(property "MPN" "CL21A226MAYNNNE"
			(at 0 0 180)
			(unlocked yes)
			(layer "B.Fab")
			(hide yes)
			(effects
				(font
					(size 1 1)
					(thickness 0.15)
				)
				(justify mirror)
			)
		)
		(property "Val" "22u"
			(at 0 0 180)
			(unlocked yes)
			(layer "B.Fab")
			(hide yes)
			(effects
				(font
					(size 1 1)
					(thickness 0.15)
				)
				(justify mirror)
			)
		)
		(property "Voltage" "25V"
			(at 0 0 180)
			(unlocked yes)
			(layer "B.Fab")
			(hide yes)
			(effects
				(font
					(size 1 1)
					(thickness 0.15)
				)
				(justify mirror)
			)
		)
		(property "Dielectric" "X5R"
			(at 0 0 180)
			(unlocked yes)
			(layer "B.Fab")
			(hide yes)
			(effects
				(font
					(size 1 1)
					(thickness 0.15)
				)
				(justify mirror)
			)
		)
		(property "Manufacturer" "Samsung Electro-Mechanics"
			(at 0 0 180)
			(unlocked yes)
			(layer "B.Fab")
			(hide yes)
			(effects
				(font
					(size 1 1)
					(thickness 0.15)
				)
				(justify mirror)
			)
		)
		(property "License" "Apache-2.0"
			(at 0 0 180)
			(unlocked yes)
			(layer "B.Fab")
			(hide yes)
			(effects
				(font
					(size 1 1)
					(thickness 0.15)
				)
				(justify mirror)
			)
		)
		(property "Author" "Antmicro"
			(at 0 0 180)
			(unlocked yes)
			(layer "B.Fab")
			(hide yes)
			(effects
				(font
					(size 1 1)
					(thickness 0.15)
				)
				(justify mirror)
			)
		)
		(property "Public" "False"
			(at 0 0 180)
			(unlocked yes)
			(layer "B.Fab")
			(hide yes)
			(effects
				(font
					(size 1 1)
					(thickness 0.15)
				)
				(justify mirror)
			)
		)
		(sheetname "/Expansion connector/")
		(sheetfile "expansion_connector.kicad_sch")
		(attr smd)
		(fp_line
			(start -0.3 0.7)
			(end 0.3 0.7)
			(stroke
				(width 0.15)
				(type solid)
			)
			(layer "B.SilkS")
		)
		(fp_line
			(start -0.3 -0.7)
			(end 0.3 -0.7)
			(stroke
				(width 0.15)
				(type solid)
			)
			(layer "B.SilkS")
		)
		(fp_rect
			(start 1.95 0.9)
			(end -1.95 -0.9)
			(stroke
				(width 0.05)
				(type default)
			)
			(fill no)
			(layer "B.CrtYd")
		)
		(fp_rect
			(start -0.95 0.675)
			(end 0.95 -0.675)
			(stroke
				(width 0.15)
				(type solid)
			)
			(fill no)
			(layer "B.Fab")
		)
		(fp_text user "License: Apache-2.0"
			(at -1.9 -4.947 0)
			(layer "B.Fab")
			(effects
				(font
					(size 0.7 0.7)
					(thickness 0.15)
				)
				(justify left bottom mirror)
			)
		)
		(fp_text user "${REFERENCE}"
			(at -1.9 -3.947 0)
			(layer "B.Fab")
			(effects
				(font
					(size 0.7 0.7)
					(thickness 0.15)
				)
				(justify left bottom mirror)
			)
		)
		(fp_text user "Author: Antmicro"
			(at -1.9 -5.947 0)
			(layer "B.Fab")
			(effects
				(font
					(size 0.7 0.7)
					(thickness 0.15)
				)
				(justify left bottom mirror)
			)
		)
		(pad "1" smd roundrect
			(at -1.1 0 180)
			(size 1.2 1.3)
			(layers "B.Cu" "B.Mask" "B.Paste")
			(roundrect_rratio 0.25)
			(net 1 "GND")
			(pintype "passive")
		)
		(pad "2" smd roundrect
			(at 1.1 0 180)
			(size 1.2 1.3)
			(layers "B.Cu" "B.Mask" "B.Paste")
			(roundrect_rratio 0.25)
			(net 307 "/Expansion connector/+5V_FMC")
			(pintype "passive")
		)
	)
	(footprint "antmicro-footprints:TP_SMD_0.75mm"
		(layer "B.Cu")
		(at 91.4 85.1 90)
		(property "Reference" "TP52"
			(at -3.2 -0.5 90)
			(layer "B.SilkS")
			(effects
				(font
					(size 0.7 0.7)
					(thickness 0.15)
				)
				(justify right top mirror)
			)
		)
		(property "Value" "TP_0.75mm_SMD"
			(at 0 -1.2 90)
			(layer "B.Fab")
			(effects
				(font
					(size 0.7 0.7)
					(thickness 0.15)
				)
				(justify right top mirror)
			)
		)
		(property "Description" "SMT test point"
			(at 0 0 90)
			(layer "B.Fab")
			(hide yes)
			(effects
				(font
					(size 1.27 1.27)
					(thickness 0.15)
				)
				(justify mirror)
			)
		)
		(property "MPN" ""
			(at 0 0 270)
			(unlocked yes)
			(layer "B.Fab")
			(hide yes)
			(effects
				(font
					(size 1 1)
					(thickness 0.15)
				)
				(justify mirror)
			)
		)
		(property "Manufacturer" ""
			(at 0 0 270)
			(unlocked yes)
			(layer "B.Fab")
			(hide yes)
			(effects
				(font
					(size 1 1)
					(thickness 0.15)
				)
				(justify mirror)
			)
		)
		(property "Author" "Antmicro"
			(at 0 0 270)
			(unlocked yes)
			(layer "B.Fab")
			(hide yes)
			(effects
				(font
					(size 1 1)
					(thickness 0.15)
				)
				(justify mirror)
			)
		)
		(property "License" "Apache-2.0"
			(at 0 0 270)
			(unlocked yes)
			(layer "B.Fab")
			(hide yes)
			(effects
				(font
					(size 1 1)
					(thickness 0.15)
				)
				(justify mirror)
			)
		)
		(sheetname "/SoM_Power/")
		(sheetfile "som_power.kicad_sch")
		(attr exclude_from_pos_files exclude_from_bom)
		(fp_circle
			(center 0 0)
			(end 0.475 0)
			(stroke
				(width 0.05)
				(type default)
			)
			(fill no)
			(layer "B.CrtYd")
		)
		(fp_text user "License: Apache-2.0"
			(at -0.4 -5.101 90)
			(layer "B.Fab")
			(effects
				(font
					(size 0.7 0.7)
					(thickness 0.15)
				)
				(justify right top mirror)
			)
		)
		(fp_text user "${REFERENCE}"
			(at -0.4 -2.7 90)
			(layer "B.Fab")
			(effects
				(font
					(size 0.7 0.7)
					(thickness 0.15)
				)
				(justify right top mirror)
			)
		)
		(fp_text user "Author: Antmicro"
			(at -0.4 -3.901 90)
			(layer "B.Fab")
			(effects
				(font
					(size 0.7 0.7)
					(thickness 0.15)
				)
				(justify right top mirror)
			)
		)
		(pad "1" smd circle
			(at 0 0 90)
			(size 0.75 0.75)
			(layers "B.Cu" "B.Mask")
			(net 563 "Net-(J1A-UFS0_REF_CLK)")
			(pinfunction "1")
			(pintype "passive")
		)
	)
	(footprint "antmicro-footprints:TP_SMD_0.75mm"
		(layer "B.Cu")
		(at 95.35 70.65 90)
		(property "Reference" "TP54"
			(at -1.435 -1.38 90)
			(layer "B.SilkS")
			(effects
				(font
					(size 0.7 0.7)
					(thickness 0.15)
				)
				(justify right top mirror)
			)
		)
		(property "Value" "TP_0.75mm_SMD"
			(at 0 -1.2 90)
			(layer "B.Fab")
			(effects
				(font
					(size 0.7 0.7)
					(thickness 0.15)
				)
				(justify right top mirror)
			)
		)
		(property "Description" "SMT test point"
			(at 0 0 90)
			(layer "B.Fab")
			(hide yes)
			(effects
				(font
					(size 1.27 1.27)
					(thickness 0.15)
				)
				(justify mirror)
			)
		)
		(property "MPN" ""
			(at 0 0 270)
			(unlocked yes)
			(layer "B.Fab")
			(hide yes)
			(effects
				(font
					(size 1 1)
					(thickness 0.15)
				)
				(justify mirror)
			)
		)
		(property "Manufacturer" ""
			(at 0 0 270)
			(unlocked yes)
			(layer "B.Fab")
			(hide yes)
			(effects
				(font
					(size 1 1)
					(thickness 0.15)
				)
				(justify mirror)
			)
		)
		(property "Author" "Antmicro"
			(at 0 0 270)
			(unlocked yes)
			(layer "B.Fab")
			(hide yes)
			(effects
				(font
					(size 1 1)
					(thickness 0.15)
				)
				(justify mirror)
			)
		)
		(property "License" "Apache-2.0"
			(at 0 0 270)
			(unlocked yes)
			(layer "B.Fab")
			(hide yes)
			(effects
				(font
					(size 1 1)
					(thickness 0.15)
				)
				(justify mirror)
			)
		)
		(sheetname "/SoM_Power/")
		(sheetfile "som_power.kicad_sch")
		(attr exclude_from_pos_files exclude_from_bom)
		(fp_circle
			(center 0 0)
			(end 0.475 0)
			(stroke
				(width 0.05)
				(type default)
			)
			(fill no)
			(layer "B.CrtYd")
		)
		(fp_text user "Author: Antmicro"
			(at -0.4 -3.901 90)
			(layer "B.Fab")
			(effects
				(font
					(size 0.7 0.7)
					(thickness 0.15)
				)
				(justify right top mirror)
			)
		)
		(fp_text user "${REFERENCE}"
			(at -0.4 -2.7 90)
			(layer "B.Fab")
			(effects
				(font
					(size 0.7 0.7)
					(thickness 0.15)
				)
				(justify right top mirror)
			)
		)
		(fp_text user "License: Apache-2.0"
			(at -0.4 -5.101 90)
			(layer "B.Fab")
			(effects
				(font
					(size 0.7 0.7)
					(thickness 0.15)
				)
				(justify right top mirror)
			)
		)
		(pad "1" smd circle
			(at 0 0 90)
			(size 0.75 0.75)
			(layers "B.Cu" "B.Mask")
			(net 793 "/SoM_Power/~{SLEEP_REQ}")
			(pinfunction "1")
			(pintype "passive")
		)
	)
)
